FILE_TYPE = MACRO_DRAWING;
SET COLOR_WIRE YELLOW;
SET COLOR_PROP ORANGE;
SET COLOR_DOT WHITE;
SET COLOR_ARC YELLOW;
SET COLOR_BODY GREEN;
SET COLOR_NOTE PURPLE;
SET PROP_DISPLAY VALUE;
SET PAGE_NUMBER P12;
FORCEADD QUANTA_TITLE_BLOCK_C..1
(5125 -2525);
FORCEPROP 1 LAST CUSTOM_TXT_CDS <NAME_2>
J 0
(1950 -2475);
FORCEPROP 1 LAST CUSTOM_TXT_CDS <NAME_1>
J 0
(1950 -2350);
FORCEPROP 1 LAST CUSTOM_TXT_CDS <Q_NUMBER>
J 0
(3722 -2422);
DISPLAY 1.212766 (3722 -2422);
FORCEPROP 1 LAST CUSTOM_TXT_CDS <Q_PROJ>
J 0
(2743 -2423);
DISPLAY 1.212766 (2743 -2423);
FORCEPROP 1 LAST CUSTOM_TXT_CDS <Q_REV>
J 0
(4941 -2422);
DISPLAY 1.212766 (4941 -2422);
FORCEPROP 1 LAST CUSTOM_TXT_CDS <CON_LAST_MODIFIED>
J 0
(3240 -2510);
DISPLAY 0.978723 (3240 -2510);
FORCEPROP 1 LAST CUSTOM_TXT_CDS <CON_PAGE_NUM> OF <CON_TOTAL_PAGES>
J 0
(4679 -2507);
DISPLAY 0.978723 (4679 -2507);
FORCEPROP 1 LAST Q_TITLE BLOCK DIAGRAM - I3C
J 0
(-4241 -2499);
DISPLAY 2.446809 (-4241 -2499);
PAINT GREEN (-4241 -2499);
FORCEPROP 1 LAST Q_DEPT 
J 1
(1362 -2476);
DISPLAY 1.957447 (1362 -2476);
PAINT GREEN (1362 -2476);
FORCEPROP 2 LAST CDS_LIB pure_quanta
J 0
(5125 -2525);
DISPLAY INVISIBLE (5125 -2525);
FORCEPROP 1 LAST CDS_LMAN_SYM_OUTLINE -9475,6775,100,-125
J 0
(5125 -2525);
DISPLAY 0.468085 (5125 -2525);
PAINT GREEN (5125 -2525);
DISPLAY INVISIBLE (5125 -2525);
FORCEPROP 1 LAST COMMENT_BODY TRUE
J 0
(5137 -2538);
DISPLAY 0.978723 (5137 -2538);
PAINT GREEN (5137 -2538);
DISPLAY INVISIBLE (5137 -2538);
FORCEPROP 2 LAST PAGE_BORDER TRUE
J 0
(-2765 2725);
DISPLAY 0.638298 (-2765 2725);
PAINT PINK (-2765 2725);
DISPLAY INVISIBLE (-2765 2725);
FORCEPROP 2 LAST CDS_XR_PAGE_TITLE CR-10 : @S9S_MB_2U_LIB.S9S_MB_2U(SCH_1):PAGE10
J 0
(-2765 2725);
DISPLAY 0.638298 (-2765 2725);
PAINT PINK (-2765 2725);
DISPLAY INVISIBLE (-2765 2725);
FORCEPROP 2 LAST CUSTOM_TXT_CDS <XR_PAGE_TITLE>
J 0
(-2765 2725);
DISPLAY 0.638298 (-2765 2725);
PAINT PINK (-2765 2725);
DISPLAY INVISIBLE (-2765 2725);
FORCEPROP 0 LAST CDS_CON_LAST_MODIFIED Thu Aug 24 16:12:01 2023
J 0
(3240 -2510);
DISPLAY INVISIBLE (3240 -2510);
FORCENOTE
$CDS_IMAGE|F0T_MB_I3C_diagram_20211222_rev1.jpg|9239|2815
(450 1025) 0;
DISPLAY LEFT (450 1025);
QUIT
